(kicad_pcb
	(version 20260206)
	(generator "pcbnew")
	(generator_version "10.0")
	(general
		(thickness 1.6)
		(legacy_teardrops no)
	)
	(paper "A4")
	(title_block
		(title "04192023_DAF0TMB3IC0_F0TG_MB_C_brd_V02_OCP.brd")
		(comment 1 "Grand Teton / footprints 7996-8001 of 8354")
	)
	(layers
		(0 "F.Cu" signal "TOP")
		(4 "In1.Cu" signal "GND")
		(6 "In2.Cu" signal "IN1")
		(8 "In3.Cu" signal "GND1")
		(10 "In4.Cu" signal "IN2")
		(12 "In5.Cu" signal "GND2")
		(14 "In6.Cu" signal "IN3")
		(16 "In7.Cu" signal "GND3")
		(18 "In8.Cu" signal "VCC")
		(20 "In9.Cu" signal "VCC1")
		(22 "In10.Cu" signal "GND4")
		(24 "In11.Cu" signal "IN4")
		(26 "In12.Cu" signal "GND5")
		(28 "In13.Cu" signal "IN5")
		(30 "In14.Cu" signal "GND6")
		(32 "In15.Cu" signal "IN6")
		(34 "In16.Cu" signal "GND7")
		(2 "B.Cu" signal "BOTTOM")
		(9 "F.Adhes" user "F.Adhesive")
		(11 "B.Adhes" user "B.Adhesive")
		(13 "F.Paste" user "Package Geometry/Pastemask Top")
		(15 "B.Paste" user "Package Geometry/Pastemask Bottom")
		(5 "F.SilkS" user "Ref Des/Silkscreen Top")
		(7 "B.SilkS" user "Ref Des/Silkscreen Bottom")
		(1 "F.Mask" user "Board Geometry/Soldermask Top")
		(3 "B.Mask" user "Board Geometry/Soldermask Bottom")
		(17 "Dwgs.User" user "User.Drawings")
		(19 "Cmts.User" user "User.Comments")
		(21 "Eco1.User" user "User.Eco1")
		(23 "Eco2.User" user "User.Eco2")
		(25 "Edge.Cuts" user "Board Geometry/Outline")
		(27 "Margin" user)
		(31 "F.CrtYd" user "Package Geometry/Place Bound Top")
		(29 "B.CrtYd" user "Package Geometry/Place Bound Bottom")
		(35 "F.Fab" user "Ref Des/Assembly Top")
		(33 "B.Fab" user "Ref Des/Assembly Bottom")
	)
	(footprint ""
		(layer "B.Cu")
		(at 367.614454 -266.00531)
		(property "Reference" "C2142"
			(at 0 0 0)
			(layer "B.SilkS")
			(hide yes)
			(effects
				(font
					(size 1.27 1.27)
				)
				(justify mirror)
			)
		)
		(property "Value" ""
			(at 0 0 0)
			(layer "B.Fab")
			(effects
				(font
					(size 1.27 1.27)
				)
				(justify mirror)
			)
		)
		(duplicate_pad_numbers_are_jumpers no)
		(fp_line
			(start -0.7874 -0.4064)
			(end -0.7874 0.4064)
			(stroke
				(width 0.1524)
				(type default)
			)
			(layer "B.SilkS")
		)
		(fp_line
			(start -0.7874 0.4064)
			(end 0.7874 0.4064)
			(stroke
				(width 0.1524)
				(type default)
			)
			(layer "B.SilkS")
		)
		(fp_line
			(start 0.7874 -0.4064)
			(end -0.7874 -0.4064)
			(stroke
				(width 0.1524)
				(type default)
			)
			(layer "B.SilkS")
		)
		(fp_line
			(start 0.7874 0.4064)
			(end 0.7874 -0.4064)
			(stroke
				(width 0.1524)
				(type default)
			)
			(layer "B.SilkS")
		)
		(fp_line
			(start -0.67945 -0.3048)
			(end -0.67945 0.3048)
			(stroke
				(width 0.1)
				(type default)
			)
			(layer "B.Fab")
		)
		(fp_line
			(start -0.67945 0.3048)
			(end -0.120396 0.3048)
			(stroke
				(width 0.1)
				(type default)
			)
			(layer "B.Fab")
		)
		(fp_line
			(start -0.12065 -0.3048)
			(end -0.67945 -0.3048)
			(stroke
				(width 0.1)
				(type default)
			)
			(layer "B.Fab")
		)
		(fp_line
			(start -0.12065 -0.2794)
			(end -0.12065 -0.3048)
			(stroke
				(width 0.1)
				(type default)
			)
			(layer "B.Fab")
		)
		(fp_line
			(start -0.120396 0.2794)
			(end 0.12065 0.2794)
			(stroke
				(width 0.1)
				(type default)
			)
			(layer "B.Fab")
		)
		(fp_line
			(start -0.120396 0.3048)
			(end -0.120396 0.2794)
			(stroke
				(width 0.1)
				(type default)
			)
			(layer "B.Fab")
		)
		(fp_line
			(start 0.12065 -0.305054)
			(end 0.12065 -0.2794)
			(stroke
				(width 0.1)
				(type default)
			)
			(layer "B.Fab")
		)
		(fp_line
			(start 0.12065 -0.2794)
			(end -0.12065 -0.2794)
			(stroke
				(width 0.1)
				(type default)
			)
			(layer "B.Fab")
		)
		(fp_line
			(start 0.12065 0.2794)
			(end 0.12065 0.3048)
			(stroke
				(width 0.1)
				(type default)
			)
			(layer "B.Fab")
		)
		(fp_line
			(start 0.12065 0.3048)
			(end 0.67945 0.3048)
			(stroke
				(width 0.1)
				(type default)
			)
			(layer "B.Fab")
		)
		(fp_line
			(start 0.67945 -0.305054)
			(end 0.12065 -0.305054)
			(stroke
				(width 0.1)
				(type default)
			)
			(layer "B.Fab")
		)
		(fp_line
			(start 0.67945 0.3048)
			(end 0.67945 -0.305054)
			(stroke
				(width 0.1)
				(type default)
			)
			(layer "B.Fab")
		)
		(pad "1" smd circle
			(at 0.40005 0 180)
			(size 0 0)
			(layers "B.Cu" "B.Mask" "B.Paste")
			(net "PVDD11_S3_P0")
		)
		(pad "2" smd circle
			(at -0.40005 0 180)
			(size 0 0)
			(layers "B.Cu" "B.Mask" "B.Paste")
			(net "GND")
		)
	)
	(footprint ""
		(layer "B.Cu")
		(at 101.668834 -272.284952 180)
		(property "Reference" "C2389"
			(at 0 0 0)
			(layer "B.SilkS")
			(hide yes)
			(effects
				(font
					(size 1.27 1.27)
				)
				(justify mirror)
			)
		)
		(property "Value" ""
			(at 0 0 0)
			(layer "B.Fab")
			(effects
				(font
					(size 1.27 1.27)
				)
				(justify mirror)
			)
		)
		(duplicate_pad_numbers_are_jumpers no)
		(fp_line
			(start 0.7874 0.4064)
			(end 0.7874 -0.4064)
			(stroke
				(width 0.1524)
				(type default)
			)
			(layer "B.SilkS")
		)
		(fp_line
			(start 0.7874 -0.4064)
			(end -0.7874 -0.4064)
			(stroke
				(width 0.1524)
				(type default)
			)
			(layer "B.SilkS")
		)
		(fp_line
			(start -0.7874 0.4064)
			(end 0.7874 0.4064)
			(stroke
				(width 0.1524)
				(type default)
			)
			(layer "B.SilkS")
		)
		(fp_line
			(start -0.7874 -0.4064)
			(end -0.7874 0.4064)
			(stroke
				(width 0.1524)
				(type default)
			)
			(layer "B.SilkS")
		)
		(fp_line
			(start 0.67945 0.3048)
			(end 0.67945 -0.305054)
			(stroke
				(width 0.1)
				(type default)
			)
			(layer "B.Fab")
		)
		(fp_line
			(start 0.67945 -0.305054)
			(end 0.12065 -0.305054)
			(stroke
				(width 0.1)
				(type default)
			)
			(layer "B.Fab")
		)
		(fp_line
			(start 0.12065 0.3048)
			(end 0.67945 0.3048)
			(stroke
				(width 0.1)
				(type default)
			)
			(layer "B.Fab")
		)
		(fp_line
			(start 0.12065 0.2794)
			(end 0.12065 0.3048)
			(stroke
				(width 0.1)
				(type default)
			)
			(layer "B.Fab")
		)
		(fp_line
			(start 0.12065 -0.2794)
			(end -0.12065 -0.2794)
			(stroke
				(width 0.1)
				(type default)
			)
			(layer "B.Fab")
		)
		(fp_line
			(start 0.12065 -0.305054)
			(end 0.12065 -0.2794)
			(stroke
				(width 0.1)
				(type default)
			)
			(layer "B.Fab")
		)
		(fp_line
			(start -0.120396 0.3048)
			(end -0.120396 0.2794)
			(stroke
				(width 0.1)
				(type default)
			)
			(layer "B.Fab")
		)
		(fp_line
			(start -0.120396 0.2794)
			(end 0.12065 0.2794)
			(stroke
				(width 0.1)
				(type default)
			)
			(layer "B.Fab")
		)
		(fp_line
			(start -0.12065 -0.2794)
			(end -0.12065 -0.3048)
			(stroke
				(width 0.1)
				(type default)
			)
			(layer "B.Fab")
		)
		(fp_line
			(start -0.12065 -0.3048)
			(end -0.67945 -0.3048)
			(stroke
				(width 0.1)
				(type default)
			)
			(layer "B.Fab")
		)
		(fp_line
			(start -0.67945 0.3048)
			(end -0.120396 0.3048)
			(stroke
				(width 0.1)
				(type default)
			)
			(layer "B.Fab")
		)
		(fp_line
			(start -0.67945 -0.3048)
			(end -0.67945 0.3048)
			(stroke
				(width 0.1)
				(type default)
			)
			(layer "B.Fab")
		)
		(pad "1" smd circle
			(at 0.40005 0)
			(size 0 0)
			(layers "B.Cu" "B.Mask" "B.Paste")
			(net "PVDDCR_CPU1_P1")
		)
		(pad "2" smd circle
			(at -0.40005 0)
			(size 0 0)
			(layers "B.Cu" "B.Mask" "B.Paste")
			(net "GND")
		)
	)
	(footprint ""
		(layer "B.Cu")
		(at 375.29135 -398.942052 90)
		(property "Reference" "C1041"
			(at 0 0 90)
			(layer "B.SilkS")
			(hide yes)
			(effects
				(font
					(size 1.27 1.27)
				)
				(justify mirror)
			)
		)
		(property "Value" ""
			(at 0 0 90)
			(layer "B.Fab")
			(effects
				(font
					(size 1.27 1.27)
				)
				(justify mirror)
			)
		)
		(duplicate_pad_numbers_are_jumpers no)
		(fp_line
			(start 0.7874 -0.4064)
			(end -0.7874 -0.4064)
			(stroke
				(width 0.1524)
				(type default)
			)
			(layer "B.SilkS")
		)
		(fp_line
			(start -0.7874 -0.4064)
			(end -0.7874 0.4064)
			(stroke
				(width 0.1524)
				(type default)
			)
			(layer "B.SilkS")
		)
		(fp_line
			(start 0.7874 0.4064)
			(end 0.7874 -0.4064)
			(stroke
				(width 0.1524)
				(type default)
			)
			(layer "B.SilkS")
		)
		(fp_line
			(start -0.7874 0.4064)
			(end 0.7874 0.4064)
			(stroke
				(width 0.1524)
				(type default)
			)
			(layer "B.SilkS")
		)
		(fp_line
			(start 0.67945 -0.305054)
			(end 0.12065 -0.305054)
			(stroke
				(width 0.1)
				(type default)
			)
			(layer "B.Fab")
		)
		(fp_line
			(start 0.12065 -0.305054)
			(end 0.12065 -0.2794)
			(stroke
				(width 0.1)
				(type default)
			)
			(layer "B.Fab")
		)
		(fp_line
			(start -0.12065 -0.3048)
			(end -0.67945 -0.3048)
			(stroke
				(width 0.1)
				(type default)
			)
			(layer "B.Fab")
		)
		(fp_line
			(start -0.67945 -0.3048)
			(end -0.67945 0.3048)
			(stroke
				(width 0.1)
				(type default)
			)
			(layer "B.Fab")
		)
		(fp_line
			(start 0.12065 -0.2794)
			(end -0.12065 -0.2794)
			(stroke
				(width 0.1)
				(type default)
			)
			(layer "B.Fab")
		)
		(fp_line
			(start -0.12065 -0.2794)
			(end -0.12065 -0.3048)
			(stroke
				(width 0.1)
				(type default)
			)
			(layer "B.Fab")
		)
		(fp_line
			(start 0.12065 0.2794)
			(end 0.12065 0.3048)
			(stroke
				(width 0.1)
				(type default)
			)
			(layer "B.Fab")
		)
		(fp_line
			(start -0.120396 0.2794)
			(end 0.12065 0.2794)
			(stroke
				(width 0.1)
				(type default)
			)
			(layer "B.Fab")
		)
		(fp_line
			(start 0.67945 0.3048)
			(end 0.67945 -0.305054)
			(stroke
				(width 0.1)
				(type default)
			)
			(layer "B.Fab")
		)
		(fp_line
			(start 0.12065 0.3048)
			(end 0.67945 0.3048)
			(stroke
				(width 0.1)
				(type default)
			)
			(layer "B.Fab")
		)
		(fp_line
			(start -0.120396 0.3048)
			(end -0.120396 0.2794)
			(stroke
				(width 0.1)
				(type default)
			)
			(layer "B.Fab")
		)
		(fp_line
			(start -0.67945 0.3048)
			(end -0.120396 0.3048)
			(stroke
				(width 0.1)
				(type default)
			)
			(layer "B.Fab")
		)
		(pad "1" smd circle
			(at 0.40005 0 270)
			(size 0 0)
			(layers "B.Cu" "B.Mask" "B.Paste")
			(net "P0V9_CPU0_RT3_2A")
		)
		(pad "2" smd circle
			(at -0.40005 0 270)
			(size 0 0)
			(layers "B.Cu" "B.Mask" "B.Paste")
			(net "GND")
		)
	)
	(footprint ""
		(layer "B.Cu")
		(at 149.243034 -203.704952 90)
		(property "Reference" "R528"
			(at 0 0 90)
			(layer "B.SilkS")
			(hide yes)
			(effects
				(font
					(size 1.27 1.27)
				)
				(justify mirror)
			)
		)
		(property "Value" ""
			(at 0 0 90)
			(layer "B.Fab")
			(effects
				(font
					(size 1.27 1.27)
				)
				(justify mirror)
			)
		)
		(duplicate_pad_numbers_are_jumpers no)
		(fp_line
			(start 0.7874 -0.4064)
			(end -0.7874 -0.4064)
			(stroke
				(width 0.1524)
				(type default)
			)
			(layer "B.SilkS")
		)
		(fp_line
			(start -0.7874 -0.4064)
			(end -0.7874 0.4064)
			(stroke
				(width 0.1524)
				(type default)
			)
			(layer "B.SilkS")
		)
		(fp_line
			(start 0.7874 0.4064)
			(end 0.7874 -0.4064)
			(stroke
				(width 0.1524)
				(type default)
			)
			(layer "B.SilkS")
		)
		(fp_line
			(start -0.7874 0.4064)
			(end 0.7874 0.4064)
			(stroke
				(width 0.1524)
				(type default)
			)
			(layer "B.SilkS")
		)
		(fp_line
			(start 0.67945 -0.305054)
			(end 0.12065 -0.305054)
			(stroke
				(width 0.1)
				(type default)
			)
			(layer "B.Fab")
		)
		(fp_line
			(start 0.12065 -0.305054)
			(end 0.12065 -0.2794)
			(stroke
				(width 0.1)
				(type default)
			)
			(layer "B.Fab")
		)
		(fp_line
			(start -0.12065 -0.3048)
			(end -0.67945 -0.3048)
			(stroke
				(width 0.1)
				(type default)
			)
			(layer "B.Fab")
		)
		(fp_line
			(start -0.67945 -0.3048)
			(end -0.67945 0.3048)
			(stroke
				(width 0.1)
				(type default)
			)
			(layer "B.Fab")
		)
		(fp_line
			(start 0.12065 -0.2794)
			(end -0.12065 -0.2794)
			(stroke
				(width 0.1)
				(type default)
			)
			(layer "B.Fab")
		)
		(fp_line
			(start -0.12065 -0.2794)
			(end -0.12065 -0.3048)
			(stroke
				(width 0.1)
				(type default)
			)
			(layer "B.Fab")
		)
		(fp_line
			(start 0.12065 0.2794)
			(end 0.12065 0.3048)
			(stroke
				(width 0.1)
				(type default)
			)
			(layer "B.Fab")
		)
		(fp_line
			(start -0.120396 0.2794)
			(end 0.12065 0.2794)
			(stroke
				(width 0.1)
				(type default)
			)
			(layer "B.Fab")
		)
		(fp_line
			(start 0.67945 0.3048)
			(end 0.67945 -0.305054)
			(stroke
				(width 0.1)
				(type default)
			)
			(layer "B.Fab")
		)
		(fp_line
			(start 0.12065 0.3048)
			(end 0.67945 0.3048)
			(stroke
				(width 0.1)
				(type default)
			)
			(layer "B.Fab")
		)
		(fp_line
			(start -0.120396 0.3048)
			(end -0.120396 0.2794)
			(stroke
				(width 0.1)
				(type default)
			)
			(layer "B.Fab")
		)
		(fp_line
			(start -0.67945 0.3048)
			(end -0.120396 0.3048)
			(stroke
				(width 0.1)
				(type default)
			)
			(layer "B.Fab")
		)
		(pad "1" smd circle
			(at 0.40005 0 270)
			(size 0 0)
			(layers "B.Cu" "B.Mask" "B.Paste")
			(net "PVDD18_S5_P1")
		)
		(pad "2" smd circle
			(at -0.40005 0 270)
			(size 0 0)
			(layers "B.Cu" "B.Mask" "B.Paste")
			(net "JTAG_CPU1_DBREQ_N")
		)
	)
	(footprint ""
		(layer "B.Cu")
		(at 125.135386 -264.354564)
		(property "Reference" "C2120"
			(at 0 0 0)
			(layer "B.SilkS")
			(hide yes)
			(effects
				(font
					(size 1.27 1.27)
				)
				(justify mirror)
			)
		)
		(property "Value" ""
			(at 0 0 0)
			(layer "B.Fab")
			(effects
				(font
					(size 1.27 1.27)
				)
				(justify mirror)
			)
		)
		(duplicate_pad_numbers_are_jumpers no)
		(fp_line
			(start -0.7874 -0.4064)
			(end -0.7874 0.4064)
			(stroke
				(width 0.1524)
				(type default)
			)
			(layer "B.SilkS")
		)
		(fp_line
			(start -0.7874 0.4064)
			(end 0.7874 0.4064)
			(stroke
				(width 0.1524)
				(type default)
			)
			(layer "B.SilkS")
		)
		(fp_line
			(start 0.7874 -0.4064)
			(end -0.7874 -0.4064)
			(stroke
				(width 0.1524)
				(type default)
			)
			(layer "B.SilkS")
		)
		(fp_line
			(start 0.7874 0.4064)
			(end 0.7874 -0.4064)
			(stroke
				(width 0.1524)
				(type default)
			)
			(layer "B.SilkS")
		)
		(fp_line
			(start -0.67945 -0.3048)
			(end -0.67945 0.3048)
			(stroke
				(width 0.1)
				(type default)
			)
			(layer "B.Fab")
		)
		(fp_line
			(start -0.67945 0.3048)
			(end -0.120396 0.3048)
			(stroke
				(width 0.1)
				(type default)
			)
			(layer "B.Fab")
		)
		(fp_line
			(start -0.12065 -0.3048)
			(end -0.67945 -0.3048)
			(stroke
				(width 0.1)
				(type default)
			)
			(layer "B.Fab")
		)
		(fp_line
			(start -0.12065 -0.2794)
			(end -0.12065 -0.3048)
			(stroke
				(width 0.1)
				(type default)
			)
			(layer "B.Fab")
		)
		(fp_line
			(start -0.120396 0.2794)
			(end 0.12065 0.2794)
			(stroke
				(width 0.1)
				(type default)
			)
			(layer "B.Fab")
		)
		(fp_line
			(start -0.120396 0.3048)
			(end -0.120396 0.2794)
			(stroke
				(width 0.1)
				(type default)
			)
			(layer "B.Fab")
		)
		(fp_line
			(start 0.12065 -0.305054)
			(end 0.12065 -0.2794)
			(stroke
				(width 0.1)
				(type default)
			)
			(layer "B.Fab")
		)
		(fp_line
			(start 0.12065 -0.2794)
			(end -0.12065 -0.2794)
			(stroke
				(width 0.1)
				(type default)
			)
			(layer "B.Fab")
		)
		(fp_line
			(start 0.12065 0.2794)
			(end 0.12065 0.3048)
			(stroke
				(width 0.1)
				(type default)
			)
			(layer "B.Fab")
		)
		(fp_line
			(start 0.12065 0.3048)
			(end 0.67945 0.3048)
			(stroke
				(width 0.1)
				(type default)
			)
			(layer "B.Fab")
		)
		(fp_line
			(start 0.67945 -0.305054)
			(end 0.12065 -0.305054)
			(stroke
				(width 0.1)
				(type default)
			)
			(layer "B.Fab")
		)
		(fp_line
			(start 0.67945 0.3048)
			(end 0.67945 -0.305054)
			(stroke
				(width 0.1)
				(type default)
			)
			(layer "B.Fab")
		)
		(pad "1" smd circle
			(at 0.40005 0 180)
			(size 0 0)
			(layers "B.Cu" "B.Mask" "B.Paste")
			(net "PVDD11_S3_P1")
		)
		(pad "2" smd circle
			(at -0.40005 0 180)
			(size 0 0)
			(layers "B.Cu" "B.Mask" "B.Paste")
			(net "GND")
		)
	)
	(footprint ""
		(layer "B.Cu")
		(at 420.968424 -420.534592)
		(property "Reference" "R680"
			(at 0 0 0)
			(layer "B.SilkS")
			(hide yes)
			(effects
				(font
					(size 1.27 1.27)
				)
				(justify mirror)
			)
		)
		(property "Value" ""
			(at 0 0 0)
			(layer "B.Fab")
			(effects
				(font
					(size 1.27 1.27)
				)
				(justify mirror)
			)
		)
		(duplicate_pad_numbers_are_jumpers no)
		(fp_line
			(start -0.32512 -0.175006)
			(end -0.32512 0.175006)
			(stroke
				(width 0.1)
				(type default)
			)
			(layer "B.Fab")
		)
		(fp_line
			(start -0.32512 0.175006)
			(end 0.32512 0.175006)
			(stroke
				(width 0.1)
				(type default)
			)
			(layer "B.Fab")
		)
		(fp_line
			(start 0.32512 -0.175006)
			(end -0.32512 -0.175006)
			(stroke
				(width 0.1)
				(type default)
			)
			(layer "B.Fab")
		)
		(fp_line
			(start 0.32512 0.175006)
			(end 0.32512 -0.175006)
			(stroke
				(width 0.1)
				(type default)
			)
			(layer "B.Fab")
		)
		(pad "1" smd rect
			(at 0.2667 0 180)
			(size 0.3048 0.381)
			(layers "B.Cu" "B.Mask" "B.Paste")
			(net "SMB_RT_CPU0_P2_ROM_MUX_1D_SCL")
		)
		(pad "2" smd rect
			(at -0.2667 0)
			(size 0.3048 0.381)
			(layers "B.Cu" "B.Mask" "B.Paste")
			(net "SMB_RT_CPU0_P2_ROM_MUX_1D_R_SCL")
		)
	)
)
